FILE_TYPE = CONNECTIVITY;
{Allegro Design Entry HDL 16.6-p007 (v16-6-112F) 10/10/2012}
"PAGE_NUMBER" = 160;
0"NC";
1"P3V3_STBY\g";
2"P3V3_STBY\g";
3"SMB_LAN_STBY_LVC3_SDA_R";
4"SMB_LAN_STBY_LVC3_SCL_R";
5"SMB_LAN_STBY_LVC3_SDA";
6"SMB_LAN_STBY_LVC3_SCL";
7"SMB_SLOTX24_STBY_LVC3_SCL_R";
8"SMB_SLOTX24_STBY_LVC3_SDA_R";
9"SMB_SLOTX24_BMC_STBY_LVC3_SCL";
10"SMB_SLOTX24_BMC_STBY_LVC3_SDA";
%"RES"
"1","(-3350,4600)","0","mstr_discrete","I4";
;
ROOM"SMBUS"
CDS_LOCATION"R1T8"
$SEC"1"
CDS_SEC"1"
CDS_LIB"mstr_discrete"
BOM_COST"SM_CONTROLLER"
WATTAGE"1/16W"
PACK_TYPE"0402"
PART_NUMBER"G21796-173"
MATERIAL"CHIP"
TOLERANCE"1%"
VALUE"20.0"
LOCATION"R1T8";
"B"
$PN"2"10;
"A"
$PN"1"8;
%"RES"
"2","(-4000,4975)","0","mstr_discrete","I46";
;
ROOM"SMBUS"
CDS_LOCATION"R1T3"
$SEC"1"
CDS_SEC"1"
CDS_LIB"mstr_discrete"
BOM_COST"SM_CONTROLLER"
SKU"B"
WATTAGE"1/16W"
MATERIAL"CHIP"
PACK_TYPE"0402"
TOLERANCE"1.0%"
VALUE"665"
PART_NUMBER"G21796-235"
LOCATION"R1T3";
"A"
$PN"1"2;
"B"
$PN"2"8;
%"P3V3_STBY"
"1","(-3650,5275)","0","mstr_symbols","I47";
;
HDL_POWER"P3V3_STBY"
BODY_TYPE"PLUMBING"
SIZE"1B"
CDS_LIB"mstr_symbols"
VOLTAGE"3.3V";
"G\NAC"1;
%"P3V3_STBY"
"1","(-4000,5275)","0","mstr_symbols","I48";
;
HDL_POWER"P3V3_STBY"
BODY_TYPE"PLUMBING"
SIZE"1B"
CDS_LIB"mstr_symbols"
VOLTAGE"3.3V";
"G\NAC"2;
%"RES"
"2","(-3650,4975)","0","mstr_discrete","I49";
;
ROOM"SMBUS"
CDS_LOCATION"R1T2"
$SEC"1"
CDS_SEC"1"
CDS_LIB"mstr_discrete"
BOM_COST"SM_CONTROLLER"
SKU"B"
WATTAGE"1/16W"
MATERIAL"CHIP"
PACK_TYPE"0402"
TOLERANCE"1.0%"
VALUE"665"
PART_NUMBER"G21796-235"
LOCATION"R1T2";
"A"
$PN"1"1;
"B"
$PN"2"7;
%"RES"
"1","(-3350,4425)","0","mstr_discrete","I50";
;
ROOM"SMBUS"
CDS_LOCATION"R1T7"
$SEC"1"
CDS_SEC"1"
CDS_LIB"mstr_discrete"
BOM_COST"SM_CONTROLLER"
WATTAGE"1/16W"
PACK_TYPE"0402"
PART_NUMBER"G21796-173"
MATERIAL"CHIP"
TOLERANCE"1%"
VALUE"20.0"
LOCATION"R1T7";
"B"
$PN"2"9;
"A"
$PN"1"7;
%"RES"
"1","(-3350,3700)","0","mstr_discrete","I51";
;
ROOM"SMBUS"
CDS_LOCATION"R9F23"
$SEC"1"
CDS_SEC"1"
CDS_LIB"mstr_discrete"
BOM_COST"SM_CONTROLLER"
WATTAGE"1/16W"
PACK_TYPE"0402"
PART_NUMBER"G21796-173"
MATERIAL"CHIP"
TOLERANCE"1%"
VALUE"20.0"
LOCATION"R9F23";
"B"
$PN"2"5;
"A"
$PN"1"3;
%"RES"
"1","(-3350,3525)","0","mstr_discrete","I52";
;
ROOM"SMBUS"
CDS_LOCATION"R9F22"
$SEC"1"
CDS_SEC"1"
CDS_LIB"mstr_discrete"
BOM_COST"SM_CONTROLLER"
WATTAGE"1/16W"
PACK_TYPE"0402"
PART_NUMBER"G21796-173"
MATERIAL"CHIP"
TOLERANCE"1%"
VALUE"20.0"
LOCATION"R9F22";
"B"
$PN"2"6;
"A"
$PN"1"4;
END.
